G04*
G04 #@! TF.GenerationSoftware,Altium Limited,Altium Designer,23.0.1 (38)*
G04*
G04 Layer_Color=7949734*
%FSLAX25Y25*%
%MOIN*%
G70*
G04*
G04 #@! TF.SameCoordinates,C48E81DB-6E20-4E2D-80E6-7C5AFAA1A21F*
G04*
G04*
G04 #@! TF.FilePolarity,Positive*
G04*
G01*
G75*
%ADD23C,0.00900*%
%ADD257R,1.38976X0.21654*%
G36*
X671457Y-266387D02*
X643898D01*
Y-244734D01*
X671457D01*
Y-266387D01*
D02*
G37*
%LPC*%
G36*
X657088Y-251616D02*
X655783D01*
X650744Y-259167D01*
Y-251616D01*
X649523D01*
Y-261221D01*
X650842D01*
X655866Y-253684D01*
Y-261221D01*
X657088D01*
Y-251616D01*
D02*
G37*
G36*
X662723Y-251449D02*
X662542D01*
X662445Y-251463D01*
X662348D01*
X662084Y-251491D01*
X661793Y-251533D01*
X661488Y-251602D01*
X661155Y-251685D01*
X660849Y-251796D01*
X660835D01*
X660808Y-251810D01*
X660766Y-251838D01*
X660710Y-251866D01*
X660572Y-251935D01*
X660391Y-252060D01*
X660183Y-252199D01*
X659975Y-252379D01*
X659780Y-252588D01*
X659600Y-252823D01*
Y-252837D01*
X659586Y-252851D01*
X659558Y-252893D01*
X659531Y-252935D01*
X659461Y-253073D01*
X659378Y-253254D01*
X659281Y-253476D01*
X659211Y-253740D01*
X659142Y-254017D01*
X659114Y-254323D01*
X660336Y-254420D01*
Y-254406D01*
Y-254378D01*
X660350Y-254336D01*
X660363Y-254267D01*
X660405Y-254114D01*
X660461Y-253906D01*
X660544Y-253684D01*
X660669Y-253462D01*
X660821Y-253254D01*
X661016Y-253059D01*
X661044Y-253046D01*
X661113Y-252990D01*
X661252Y-252907D01*
X661432Y-252823D01*
X661668Y-252740D01*
X661946Y-252657D01*
X662293Y-252601D01*
X662681Y-252588D01*
X662876D01*
X662959Y-252601D01*
X663070Y-252615D01*
X663320Y-252643D01*
X663597Y-252698D01*
X663875Y-252768D01*
X664139Y-252879D01*
X664250Y-252948D01*
X664361Y-253018D01*
X664389Y-253032D01*
X664444Y-253087D01*
X664527Y-253184D01*
X664611Y-253295D01*
X664708Y-253448D01*
X664791Y-253615D01*
X664847Y-253809D01*
X664874Y-254031D01*
Y-254059D01*
Y-254114D01*
X664860Y-254211D01*
X664833Y-254323D01*
X664791Y-254461D01*
X664722Y-254600D01*
X664638Y-254739D01*
X664513Y-254878D01*
X664500Y-254892D01*
X664430Y-254933D01*
X664375Y-254975D01*
X664319Y-255003D01*
X664236Y-255044D01*
X664139Y-255100D01*
X664014Y-255141D01*
X663875Y-255197D01*
X663722Y-255252D01*
X663542Y-255322D01*
X663348Y-255377D01*
X663126Y-255447D01*
X662876Y-255502D01*
X662598Y-255572D01*
X662584D01*
X662529Y-255586D01*
X662445Y-255599D01*
X662348Y-255627D01*
X662223Y-255655D01*
X662071Y-255697D01*
X661918Y-255738D01*
X661751Y-255780D01*
X661390Y-255877D01*
X661044Y-255974D01*
X660877Y-256030D01*
X660724Y-256085D01*
X660585Y-256127D01*
X660474Y-256182D01*
X660461D01*
X660433Y-256196D01*
X660391Y-256224D01*
X660336Y-256252D01*
X660183Y-256335D01*
X660003Y-256446D01*
X659794Y-256599D01*
X659586Y-256765D01*
X659392Y-256960D01*
X659225Y-257168D01*
X659211Y-257196D01*
X659156Y-257265D01*
X659100Y-257390D01*
X659017Y-257557D01*
X658948Y-257751D01*
X658878Y-257987D01*
X658837Y-258250D01*
X658823Y-258528D01*
Y-258653D01*
X658850Y-258806D01*
X658878Y-259000D01*
X658934Y-259222D01*
X659003Y-259458D01*
X659114Y-259708D01*
X659267Y-259972D01*
Y-259985D01*
X659281Y-259999D01*
X659350Y-260083D01*
X659447Y-260208D01*
X659586Y-260346D01*
X659766Y-260513D01*
X659989Y-260693D01*
X660239Y-260860D01*
X660530Y-261013D01*
X660544D01*
X660572Y-261027D01*
X660613Y-261040D01*
X660669Y-261068D01*
X660752Y-261096D01*
X660849Y-261138D01*
X661071Y-261193D01*
X661335Y-261262D01*
X661654Y-261332D01*
X662001Y-261373D01*
X662376Y-261387D01*
X662598D01*
X662709Y-261373D01*
X662834D01*
X662973Y-261360D01*
X663139Y-261346D01*
X663486Y-261290D01*
X663847Y-261235D01*
X664208Y-261138D01*
X664555Y-261013D01*
X664569D01*
X664597Y-260999D01*
X664638Y-260971D01*
X664694Y-260943D01*
X664860Y-260860D01*
X665055Y-260735D01*
X665277Y-260568D01*
X665513Y-260374D01*
X665735Y-260138D01*
X665943Y-259875D01*
Y-259861D01*
X665971Y-259833D01*
X665985Y-259791D01*
X666026Y-259736D01*
X666054Y-259666D01*
X666096Y-259583D01*
X666193Y-259375D01*
X666290Y-259111D01*
X666373Y-258820D01*
X666429Y-258487D01*
X666457Y-258139D01*
X665263Y-258028D01*
Y-258042D01*
Y-258056D01*
X665249Y-258098D01*
Y-258153D01*
X665221Y-258278D01*
X665180Y-258459D01*
X665124Y-258639D01*
X665069Y-258847D01*
X664971Y-259042D01*
X664874Y-259222D01*
X664860Y-259236D01*
X664819Y-259292D01*
X664749Y-259389D01*
X664638Y-259486D01*
X664500Y-259611D01*
X664347Y-259736D01*
X664139Y-259861D01*
X663917Y-259972D01*
X663903D01*
X663889Y-259985D01*
X663847Y-259999D01*
X663806Y-260013D01*
X663667Y-260055D01*
X663486Y-260110D01*
X663264Y-260166D01*
X663015Y-260208D01*
X662737Y-260235D01*
X662431Y-260249D01*
X662307D01*
X662168Y-260235D01*
X662001Y-260222D01*
X661807Y-260194D01*
X661585Y-260166D01*
X661363Y-260110D01*
X661155Y-260041D01*
X661127Y-260027D01*
X661057Y-259999D01*
X660960Y-259944D01*
X660835Y-259888D01*
X660710Y-259791D01*
X660572Y-259694D01*
X660433Y-259583D01*
X660322Y-259444D01*
X660308Y-259430D01*
X660280Y-259375D01*
X660239Y-259305D01*
X660183Y-259194D01*
X660127Y-259083D01*
X660086Y-258945D01*
X660058Y-258792D01*
X660044Y-258625D01*
Y-258611D01*
Y-258542D01*
X660058Y-258459D01*
X660072Y-258348D01*
X660113Y-258237D01*
X660155Y-258098D01*
X660225Y-257959D01*
X660322Y-257834D01*
X660336Y-257820D01*
X660377Y-257779D01*
X660433Y-257723D01*
X660530Y-257640D01*
X660641Y-257557D01*
X660794Y-257459D01*
X660974Y-257362D01*
X661182Y-257279D01*
X661196Y-257265D01*
X661266Y-257251D01*
X661377Y-257209D01*
X661446Y-257196D01*
X661543Y-257168D01*
X661640Y-257126D01*
X661765Y-257099D01*
X661904Y-257057D01*
X662071Y-257015D01*
X662237Y-256974D01*
X662431Y-256918D01*
X662654Y-256862D01*
X662889Y-256807D01*
X662903D01*
X662945Y-256793D01*
X663015Y-256779D01*
X663098Y-256751D01*
X663209Y-256724D01*
X663334Y-256696D01*
X663611Y-256613D01*
X663917Y-256516D01*
X664236Y-256418D01*
X664513Y-256321D01*
X664638Y-256266D01*
X664749Y-256210D01*
X664763D01*
X664777Y-256196D01*
X664860Y-256141D01*
X664985Y-256071D01*
X665124Y-255960D01*
X665291Y-255835D01*
X665457Y-255683D01*
X665624Y-255502D01*
X665763Y-255308D01*
X665777Y-255280D01*
X665818Y-255211D01*
X665874Y-255100D01*
X665929Y-254961D01*
X665985Y-254781D01*
X666040Y-254572D01*
X666082Y-254350D01*
X666096Y-254114D01*
Y-254100D01*
Y-254086D01*
Y-254045D01*
Y-253989D01*
X666068Y-253851D01*
X666040Y-253670D01*
X665999Y-253462D01*
X665929Y-253226D01*
X665832Y-252990D01*
X665693Y-252754D01*
Y-252740D01*
X665679Y-252726D01*
X665610Y-252643D01*
X665513Y-252532D01*
X665388Y-252393D01*
X665221Y-252240D01*
X665013Y-252074D01*
X664763Y-251921D01*
X664486Y-251782D01*
X664472D01*
X664444Y-251769D01*
X664402Y-251755D01*
X664347Y-251727D01*
X664278Y-251699D01*
X664180Y-251671D01*
X663972Y-251616D01*
X663708Y-251560D01*
X663403Y-251505D01*
X663084Y-251463D01*
X662723Y-251449D01*
D02*
G37*
%LPD*%
D23*
X667604Y-218376D02*
X665605D01*
X666604D01*
Y-221375D01*
X664605D02*
X663605D01*
X664105D01*
Y-219376D01*
X664605D01*
X662106Y-221375D02*
Y-219376D01*
X661606D01*
X661106Y-219876D01*
Y-221375D01*
Y-219876D01*
X660606Y-219376D01*
X660106Y-219876D01*
Y-221375D01*
X657607D02*
X658607D01*
X659107Y-220875D01*
Y-219876D01*
X658607Y-219376D01*
X657607D01*
X657107Y-219876D01*
Y-220375D01*
X659107D01*
X651109Y-218876D02*
X651609Y-218376D01*
X652609D01*
X653109Y-218876D01*
Y-220875D01*
X652609Y-221375D01*
X651609D01*
X651109Y-220875D01*
X649610Y-219376D02*
X648610D01*
X648110Y-219876D01*
Y-221375D01*
X649610D01*
X650110Y-220875D01*
X649610Y-220375D01*
X648110D01*
X647111Y-219376D02*
Y-221375D01*
Y-220375D01*
X646611Y-219876D01*
X646111Y-219376D01*
X645611D01*
X642112Y-218376D02*
Y-221375D01*
X643612D01*
X644111Y-220875D01*
Y-219876D01*
X643612Y-219376D01*
X642112D01*
X638113Y-218376D02*
Y-220375D01*
X637114Y-221375D01*
X636114Y-220375D01*
Y-218376D01*
X635114Y-218876D02*
X634615Y-218376D01*
X633615D01*
X633115Y-218876D01*
Y-219376D01*
X633615Y-219876D01*
X633115Y-220375D01*
Y-220875D01*
X633615Y-221375D01*
X634615D01*
X635114Y-220875D01*
Y-220375D01*
X634615Y-219876D01*
X635114Y-219376D01*
Y-218876D01*
X634615Y-219876D02*
X633615D01*
X667604Y-227134D02*
Y-224135D01*
X666604Y-225134D01*
X665605Y-224135D01*
Y-227134D01*
X664605D02*
X663605D01*
X664105D01*
Y-225134D01*
X664605D01*
X662106Y-227134D02*
Y-224135D01*
Y-226134D02*
X660606Y-225134D01*
X662106Y-226134D02*
X660606Y-227134D01*
X657607D02*
X658607D01*
X659107Y-226634D01*
Y-225634D01*
X658607Y-225134D01*
X657607D01*
X657107Y-225634D01*
Y-226134D01*
X659107D01*
X653109Y-224135D02*
Y-227134D01*
X651109D01*
X649610Y-225134D02*
X648610D01*
X648110Y-225634D01*
Y-227134D01*
X649610D01*
X650110Y-226634D01*
X649610Y-226134D01*
X648110D01*
X647111Y-227134D02*
Y-225134D01*
X646611D01*
X646111Y-225634D01*
Y-227134D01*
Y-225634D01*
X645611Y-225134D01*
X645111Y-225634D01*
Y-227134D01*
X644111Y-224135D02*
Y-227134D01*
X642612D01*
X642112Y-226634D01*
Y-226134D01*
Y-225634D01*
X642612Y-225134D01*
X644111D01*
X639613Y-227134D02*
X640613D01*
X641113Y-226634D01*
Y-225634D01*
X640613Y-225134D01*
X639613D01*
X639113Y-225634D01*
Y-226134D01*
X641113D01*
X637614Y-224635D02*
Y-225134D01*
X638113D01*
X637114D01*
X637614D01*
Y-226634D01*
X637114Y-227134D01*
X635114Y-225134D02*
X634115D01*
X633615Y-225634D01*
Y-227134D01*
X635114D01*
X635614Y-226634D01*
X635114Y-226134D01*
X633615D01*
X667604Y-232893D02*
Y-230893D01*
X666604Y-229894D01*
X665605Y-230893D01*
Y-232893D01*
Y-231393D01*
X667604D01*
X664605Y-229894D02*
Y-232893D01*
Y-231393D01*
X664105Y-230893D01*
X663105D01*
X662606Y-231393D01*
Y-232893D01*
X661606D02*
Y-230893D01*
X661106D01*
X660606Y-231393D01*
Y-232893D01*
Y-231393D01*
X660106Y-230893D01*
X659607Y-231393D01*
Y-232893D01*
X658107Y-230893D02*
X657107D01*
X656607Y-231393D01*
Y-232893D01*
X658107D01*
X658607Y-232393D01*
X658107Y-231893D01*
X656607D01*
X653609Y-229894D02*
Y-232893D01*
X655108D01*
X655608Y-232393D01*
Y-231393D01*
X655108Y-230893D01*
X653609D01*
X649610Y-229894D02*
Y-232893D01*
X648110D01*
X647610Y-232393D01*
Y-231893D01*
X648110Y-231393D01*
X649610D01*
X648110D01*
X647610Y-230893D01*
Y-230394D01*
X648110Y-229894D01*
X649610D01*
X646611Y-230893D02*
Y-232393D01*
X646111Y-232893D01*
X644611D01*
Y-233393D01*
X645111Y-233892D01*
X645611D01*
X644611Y-232893D02*
Y-230893D01*
X643112D02*
X642112D01*
X641612Y-231393D01*
Y-232893D01*
X643112D01*
X643612Y-232393D01*
X643112Y-231893D01*
X641612D01*
X639613Y-233892D02*
X639113D01*
X638613Y-233393D01*
Y-230893D01*
X640113D01*
X640613Y-231393D01*
Y-232393D01*
X640113Y-232893D01*
X638613D01*
X637114D02*
X636114D01*
X635614Y-232393D01*
Y-231393D01*
X636114Y-230893D01*
X637114D01*
X637614Y-231393D01*
Y-232393D01*
X637114Y-232893D01*
X634615Y-230893D02*
Y-232393D01*
X634115Y-232893D01*
X633615Y-232393D01*
X633115Y-232893D01*
X632615Y-232393D01*
Y-230893D01*
X631616Y-232893D02*
X630616D01*
X631116D01*
Y-230893D01*
X631616D01*
X665605Y-236652D02*
X666604D01*
X666104D01*
Y-239151D01*
X666604Y-239651D01*
X667104D01*
X667604Y-239151D01*
X664605Y-237652D02*
Y-239151D01*
X664105Y-239651D01*
X662606D01*
Y-237652D01*
X661606Y-239651D02*
X660606D01*
X661106D01*
Y-236652D01*
X661606D01*
X659107Y-239651D02*
X658107D01*
X658607D01*
Y-237652D01*
X659107D01*
X656108D02*
X655108D01*
X654608Y-238152D01*
Y-239651D01*
X656108D01*
X656607Y-239151D01*
X656108Y-238651D01*
X654608D01*
X653609Y-239651D02*
Y-237652D01*
X652109D01*
X651609Y-238152D01*
Y-239651D01*
X645611Y-237152D02*
X646111Y-236652D01*
X647111D01*
X647610Y-237152D01*
Y-237652D01*
X647111Y-238152D01*
X646111D01*
X645611Y-238651D01*
Y-239151D01*
X646111Y-239651D01*
X647111D01*
X647610Y-239151D01*
X644111Y-237152D02*
Y-237652D01*
X644611D01*
X643612D01*
X644111D01*
Y-239151D01*
X643612Y-239651D01*
X642112D02*
Y-239151D01*
X641612D01*
Y-239651D01*
X642112D01*
X634615Y-236652D02*
X635614D01*
X635114D01*
Y-239151D01*
X635614Y-239651D01*
X636114D01*
X636614Y-239151D01*
X633115Y-237652D02*
X632115D01*
X631616Y-238152D01*
Y-239651D01*
X633115D01*
X633615Y-239151D01*
X633115Y-238651D01*
X631616D01*
X630616Y-239651D02*
Y-237652D01*
X630116D01*
X629616Y-238152D01*
Y-239651D01*
Y-238152D01*
X629116Y-237652D01*
X628617Y-238152D01*
Y-239651D01*
X626117D02*
X627117D01*
X627617Y-239151D01*
Y-238152D01*
X627117Y-237652D01*
X626117D01*
X625618Y-238152D01*
Y-238651D01*
X627617D01*
X624618Y-239651D02*
X623118D01*
X622618Y-239151D01*
X623118Y-238651D01*
X624118D01*
X624618Y-238152D01*
X624118Y-237652D01*
X622618D01*
X276491Y-369099D02*
X276991Y-369599D01*
Y-370598D01*
X276491Y-371098D01*
X274492D01*
X273992Y-370598D01*
Y-369599D01*
X274492Y-369099D01*
X276991Y-366100D02*
Y-368099D01*
X275491D01*
X275991Y-367099D01*
Y-366599D01*
X275491Y-366100D01*
X274492D01*
X273992Y-366599D01*
Y-367599D01*
X274492Y-368099D01*
X276491Y-365100D02*
X276991Y-364600D01*
Y-363600D01*
X276491Y-363101D01*
X275991D01*
X275491Y-363600D01*
Y-364100D01*
Y-363600D01*
X274991Y-363101D01*
X274492D01*
X273992Y-363600D01*
Y-364600D01*
X274492Y-365100D01*
X269891Y-369099D02*
X270391Y-369599D01*
Y-370598D01*
X269891Y-371098D01*
X267892D01*
X267392Y-370598D01*
Y-369599D01*
X267892Y-369099D01*
X270391Y-366100D02*
Y-368099D01*
X268891D01*
X269391Y-367099D01*
Y-366599D01*
X268891Y-366100D01*
X267892D01*
X267392Y-366599D01*
Y-367599D01*
X267892Y-368099D01*
X267392Y-363101D02*
Y-365100D01*
X269391Y-363101D01*
X269891D01*
X270391Y-363600D01*
Y-364600D01*
X269891Y-365100D01*
X260391Y-369099D02*
X260891Y-369599D01*
Y-370598D01*
X260391Y-371098D01*
X258391D01*
X257892Y-370598D01*
Y-369599D01*
X258391Y-369099D01*
X260891Y-366100D02*
Y-368099D01*
X259391D01*
X259891Y-367099D01*
Y-366599D01*
X259391Y-366100D01*
X258391D01*
X257892Y-366599D01*
Y-367599D01*
X258391Y-368099D01*
X257892Y-365100D02*
Y-364100D01*
Y-364600D01*
X260891D01*
X260391Y-365100D01*
X253291Y-369099D02*
X253791Y-369599D01*
Y-370598D01*
X253291Y-371098D01*
X251291D01*
X250792Y-370598D01*
Y-369599D01*
X251291Y-369099D01*
X253791Y-366100D02*
Y-368099D01*
X252291D01*
X252791Y-367099D01*
Y-366599D01*
X252291Y-366100D01*
X251291D01*
X250792Y-366599D01*
Y-367599D01*
X251291Y-368099D01*
X253291Y-365100D02*
X253791Y-364600D01*
Y-363600D01*
X253291Y-363101D01*
X251291D01*
X250792Y-363600D01*
Y-364600D01*
X251291Y-365100D01*
X253291D01*
X244191Y-369099D02*
X244691Y-369599D01*
Y-370598D01*
X244191Y-371098D01*
X242192D01*
X241692Y-370598D01*
Y-369599D01*
X242192Y-369099D01*
X241692Y-366599D02*
X244691D01*
X243191Y-368099D01*
Y-366100D01*
X242192Y-365100D02*
X241692Y-364600D01*
Y-363600D01*
X242192Y-363101D01*
X244191D01*
X244691Y-363600D01*
Y-364600D01*
X244191Y-365100D01*
X243691D01*
X243191Y-364600D01*
Y-363101D01*
X237391Y-369099D02*
X237891Y-369599D01*
Y-370598D01*
X237391Y-371098D01*
X235391D01*
X234892Y-370598D01*
Y-369599D01*
X235391Y-369099D01*
X234892Y-366599D02*
X237891D01*
X236391Y-368099D01*
Y-366100D01*
X237391Y-365100D02*
X237891Y-364600D01*
Y-363600D01*
X237391Y-363101D01*
X236891D01*
X236391Y-363600D01*
X235891Y-363101D01*
X235391D01*
X234892Y-363600D01*
Y-364600D01*
X235391Y-365100D01*
X235891D01*
X236391Y-364600D01*
X236891Y-365100D01*
X237391D01*
X236391Y-364600D02*
Y-363600D01*
X225891Y-369099D02*
X226391Y-369599D01*
Y-370598D01*
X225891Y-371098D01*
X223891D01*
X223392Y-370598D01*
Y-369599D01*
X223891Y-369099D01*
X223392Y-366599D02*
X226391D01*
X224891Y-368099D01*
Y-366100D01*
X226391Y-365100D02*
Y-363101D01*
X225891D01*
X223891Y-365100D01*
X223392D01*
X218991Y-369099D02*
X219491Y-369599D01*
Y-370598D01*
X218991Y-371098D01*
X216991D01*
X216492Y-370598D01*
Y-369599D01*
X216991Y-369099D01*
X216492Y-366599D02*
X219491D01*
X217991Y-368099D01*
Y-366100D01*
X219491Y-363101D02*
X218991Y-364100D01*
X217991Y-365100D01*
X216991D01*
X216492Y-364600D01*
Y-363600D01*
X216991Y-363101D01*
X217491D01*
X217991Y-363600D01*
Y-365100D01*
X211554Y-367439D02*
X212054Y-367939D01*
Y-368939D01*
X211554Y-369439D01*
X209555D01*
X209055Y-368939D01*
Y-367939D01*
X209555Y-367439D01*
X209055Y-364940D02*
X212054D01*
X210555Y-366440D01*
Y-364440D01*
X212054Y-361441D02*
Y-363440D01*
X210555D01*
X211054Y-362441D01*
Y-361941D01*
X210555Y-361441D01*
X209555D01*
X209055Y-361941D01*
Y-362941D01*
X209555Y-363440D01*
X204566Y-367242D02*
X205066Y-367742D01*
Y-368742D01*
X204566Y-369242D01*
X202567D01*
X202067Y-368742D01*
Y-367742D01*
X202567Y-367242D01*
X202067Y-364743D02*
X205066D01*
X203567Y-366243D01*
Y-364243D01*
X202067Y-361744D02*
X205066D01*
X203567Y-363244D01*
Y-361244D01*
D257*
X575591Y-255561D02*
D03*
M02*
